(kicad_pcb
	(version 20241229)
	(generator "pcbnew")
	(generator_version "9.0")
	(general
		(thickness 1.62)
		(legacy_teardrops no)
	)
	(paper "A4")
	(title_block
		(title "OCuLink to 10GbE adapter")
		(date "2026-02-23")
		(rev "1.1.0")
		(company "Antmicro Ltd")
		(comment 1 "www.antmicro.com")
		(comment 9 "footprints 209-213 of 510")
	)
	(layers
		(0 "F.Cu" signal)
		(4 "In1.Cu" signal)
		(6 "In2.Cu" signal)
		(8 "In3.Cu" signal)
		(10 "In4.Cu" signal)
		(12 "In5.Cu" signal)
		(14 "In6.Cu" signal)
		(2 "B.Cu" signal)
		(9 "F.Adhes" user "F.Adhesive")
		(11 "B.Adhes" user "B.Adhesive")
		(13 "F.Paste" user)
		(15 "B.Paste" user)
		(5 "F.SilkS" user "F.Silkscreen")
		(7 "B.SilkS" user "B.Silkscreen")
		(1 "F.Mask" user)
		(3 "B.Mask" user)
		(17 "Dwgs.User" user "User.Drawings")
		(19 "Cmts.User" user "User.Comments")
		(21 "Eco1.User" user "User.Eco1")
		(23 "Eco2.User" user "User.Eco2")
		(25 "Edge.Cuts" user)
		(27 "Margin" user)
		(31 "F.CrtYd" user "F.Courtyard")
		(29 "B.CrtYd" user "B.Courtyard")
		(35 "F.Fab" user)
		(33 "B.Fab" user)
	)
	(footprint "antmicro-footprints:R_0402_1005Metric"
		(layer "F.Cu")
		(at 101.3 106.15 180)
		(descr "Resistor SMD 0402")
		(tags "resistor SMD 0402")
		(property "Reference" "R79"
			(at 0.8 -15.425 0)
			(layer "F.SilkS")
			(effects
				(font
					(size 0.7 0.7)
					(thickness 0.15)
				)
				(justify left bottom)
			)
		)
		(property "Value" "R_100k_0402"
			(at -1.011843 1.772046 0)
			(layer "F.Fab")
			(hide yes)
			(effects
				(font
					(size 0.7 0.7)
					(thickness 0.15)
				)
				(justify right top)
			)
		)
		(property "Datasheet" "https://www.bourns.com/docs/product-datasheets/cr.pdf"
			(at 0 0 0)
			(layer "F.Fab")
			(hide yes)
			(effects
				(font
					(size 1.27 1.27)
					(thickness 0.15)
				)
			)
		)
		(property "Description" "SMD Chip Resistor, 100 kohm, ± 1%, 62.5 mW, 0402 [1005 Metric], Thick Film, General Purpose"
			(at 0 0 0)
			(layer "F.Fab")
			(hide yes)
			(effects
				(font
					(size 1.27 1.27)
					(thickness 0.15)
				)
			)
		)
		(property "MPN" "CR0402-FX-1003GLF"
			(at 0 0 180)
			(unlocked yes)
			(layer "F.Fab")
			(hide yes)
			(effects
				(font
					(size 1 1)
					(thickness 0.15)
				)
			)
		)
		(property "Manufacturer" "Bourns"
			(at 0 0 180)
			(unlocked yes)
			(layer "F.Fab")
			(hide yes)
			(effects
				(font
					(size 1 1)
					(thickness 0.15)
				)
			)
		)
		(property "License" "Apache-2.0"
			(at 0 0 180)
			(unlocked yes)
			(layer "F.Fab")
			(hide yes)
			(effects
				(font
					(size 1 1)
					(thickness 0.15)
				)
			)
		)
		(property "Author" "Antmicro"
			(at 0 0 180)
			(unlocked yes)
			(layer "F.Fab")
			(hide yes)
			(effects
				(font
					(size 1 1)
					(thickness 0.15)
				)
			)
		)
		(property "Val" "100k"
			(at 0 0 180)
			(unlocked yes)
			(layer "F.Fab")
			(hide yes)
			(effects
				(font
					(size 1 1)
					(thickness 0.15)
				)
			)
		)
		(property "Tolerance" "1%"
			(at 0 0 180)
			(unlocked yes)
			(layer "F.Fab")
			(hide yes)
			(effects
				(font
					(size 1 1)
					(thickness 0.15)
				)
			)
		)
		(sheetname "/X710-AT2 Misc/")
		(sheetfile "x710-at2-mics.kicad_sch")
		(attr smd)
		(fp_rect
			(start -0.925 -0.47)
			(end 0.925 0.47)
			(stroke
				(width 0.05)
				(type default)
			)
			(fill no)
			(layer "F.CrtYd")
		)
		(fp_rect
			(start -0.5 -0.25)
			(end 0.5 0.25)
			(stroke
				(width 0.15)
				(type solid)
			)
			(fill no)
			(layer "F.Fab")
		)
		(pad "1" smd roundrect
			(at -0.48 0 180)
			(size 0.59 0.64)
			(layers "F.Cu" "F.Mask" "F.Paste")
			(roundrect_rratio 0.25)
			(net 361 "/X710-AT2 Misc/NCSI.TXD_1")
			(pintype "passive")
		)
		(pad "2" smd roundrect
			(at 0.48 0 180)
			(size 0.59 0.64)
			(layers "F.Cu" "F.Mask" "F.Paste")
			(roundrect_rratio 0.25)
			(net 7 "+3V3")
			(pintype "passive")
		)
	)
	(footprint "antmicro-footprints:C_0603_1608Metric_EIA"
		(layer "F.Cu")
		(at 77.2 82.3 180)
		(descr "Capacitor SMD 0603, IPC-7351 Density Level A")
		(tags "Capacitor 0603")
		(property "Reference" "C154"
			(at -1.4 7.586 0)
			(layer "F.SilkS")
			(effects
				(font
					(size 0.7 0.7)
					(thickness 0.15)
				)
				(justify right top)
			)
		)
		(property "Value" "C_22u_16V_0603"
			(at -1.42757 1.770288 0)
			(layer "F.Fab")
			(hide yes)
			(effects
				(font
					(size 0.7 0.7)
					(thickness 0.15)
				)
				(justify right top)
			)
		)
		(property "Datasheet" "https://product.samsungsem.com/mlcc/CL10A226MO7JZN.do"
			(at 0 0 0)
			(layer "F.Fab")
			(hide yes)
			(effects
				(font
					(size 1.27 1.27)
					(thickness 0.15)
				)
			)
		)
		(property "Description" "SMD Multilayer Ceramic Capacitor"
			(at 0 0 0)
			(layer "F.Fab")
			(hide yes)
			(effects
				(font
					(size 1.27 1.27)
					(thickness 0.15)
				)
			)
		)
		(property "MPN" "CL10A226MO7JZNC"
			(at 0 0 180)
			(unlocked yes)
			(layer "F.Fab")
			(hide yes)
			(effects
				(font
					(size 1 1)
					(thickness 0.15)
				)
			)
		)
		(property "Manufacturer" "Samsung Electro-Mechanics"
			(at 0 0 180)
			(unlocked yes)
			(layer "F.Fab")
			(hide yes)
			(effects
				(font
					(size 1 1)
					(thickness 0.15)
				)
			)
		)
		(property "License" "Apache-2.0"
			(at 0 0 180)
			(unlocked yes)
			(layer "F.Fab")
			(hide yes)
			(effects
				(font
					(size 1 1)
					(thickness 0.15)
				)
			)
		)
		(property "Author" "Antmicro"
			(at 0 0 180)
			(unlocked yes)
			(layer "F.Fab")
			(hide yes)
			(effects
				(font
					(size 1 1)
					(thickness 0.15)
				)
			)
		)
		(property "Val" "22u"
			(at 0 0 180)
			(unlocked yes)
			(layer "F.Fab")
			(hide yes)
			(effects
				(font
					(size 1 1)
					(thickness 0.15)
				)
			)
		)
		(property "Voltage" "16V"
			(at 0 0 180)
			(unlocked yes)
			(layer "F.Fab")
			(hide yes)
			(effects
				(font
					(size 1 1)
					(thickness 0.15)
				)
			)
		)
		(property "Dielectric" ""
			(at 0 0 180)
			(unlocked yes)
			(layer "F.Fab")
			(hide yes)
			(effects
				(font
					(size 1 1)
					(thickness 0.15)
				)
			)
		)
		(sheetname "/X710-AT2 power/")
		(sheetfile "x710-at2-power.kicad_sch")
		(attr smd)
		(fp_line
			(start -0.15 0.55)
			(end 0.15 0.55)
			(stroke
				(width 0.15)
				(type solid)
			)
			(layer "F.SilkS")
		)
		(fp_line
			(start -0.15 -0.55)
			(end 0.15 -0.55)
			(stroke
				(width 0.15)
				(type solid)
			)
			(layer "F.SilkS")
		)
		(fp_rect
			(start -1.25 -0.65)
			(end 1.25 0.65)
			(stroke
				(width 0.05)
				(type solid)
			)
			(fill no)
			(layer "F.CrtYd")
		)
		(fp_rect
			(start -0.8 -0.45)
			(end 0.8 0.45)
			(stroke
				(width 0.15)
				(type solid)
			)
			(fill no)
			(layer "F.Fab")
		)
		(pad "1" smd roundrect
			(at -0.7 0 180)
			(size 0.8 1.1)
			(layers "F.Cu" "F.Mask" "F.Paste")
			(roundrect_rratio 0.2)
			(net 28 "GND")
			(pintype "passive")
		)
		(pad "2" smd roundrect
			(at 0.7 0 180)
			(size 0.8 1.1)
			(layers "F.Cu" "F.Mask" "F.Paste")
			(roundrect_rratio 0.2)
			(net 7 "+3V3")
			(pintype "passive")
		)
	)
	(footprint "antmicro-footprints:C_0402_1005Metric"
		(layer "F.Cu")
		(at 104.498001 62.778655 -90)
		(descr "Capacitor SMD 0402")
		(tags "capacitor SMD 0402")
		(property "Reference" "C190"
			(at 1.406345 -2.501999 270)
			(layer "F.SilkS")
			(effects
				(font
					(size 0.7 0.7)
					(thickness 0.15)
				)
				(justify left bottom)
			)
		)
		(property "Value" "C_220n_16V_0402"
			(at -1.022927 2.155213 270)
			(layer "F.Fab")
			(hide yes)
			(effects
				(font
					(size 0.7 0.7)
					(thickness 0.15)
				)
				(justify left bottom)
			)
		)
		(property "Datasheet" "https://www.murata.com/products/productdetail?partno=GRM155R71C224KA12%23"
			(at 0 0 270)
			(layer "F.Fab")
			(hide yes)
			(effects
				(font
					(size 1.27 1.27)
					(thickness 0.15)
				)
			)
		)
		(property "Description" "SMD Multilayer Ceramic Capacitor, 0.22 µF, 16 V, 0402 [1005 Metric], ± 10%, X7R, GRM Series"
			(at 0 0 270)
			(layer "F.Fab")
			(hide yes)
			(effects
				(font
					(size 1.27 1.27)
					(thickness 0.15)
				)
			)
		)
		(property "MPN" "GRM155R71C224KA12D"
			(at 0 0 270)
			(unlocked yes)
			(layer "F.Fab")
			(hide yes)
			(effects
				(font
					(size 1 1)
					(thickness 0.15)
				)
			)
		)
		(property "Manufacturer" "Murata"
			(at 0 0 270)
			(unlocked yes)
			(layer "F.Fab")
			(hide yes)
			(effects
				(font
					(size 1 1)
					(thickness 0.15)
				)
			)
		)
		(property "License" "Apache-2.0"
			(at 0 0 270)
			(unlocked yes)
			(layer "F.Fab")
			(hide yes)
			(effects
				(font
					(size 1 1)
					(thickness 0.15)
				)
			)
		)
		(property "Author" "Antmicro"
			(at 0 0 270)
			(unlocked yes)
			(layer "F.Fab")
			(hide yes)
			(effects
				(font
					(size 1 1)
					(thickness 0.15)
				)
			)
		)
		(property "Val" "220n"
			(at 0 0 270)
			(unlocked yes)
			(layer "F.Fab")
			(hide yes)
			(effects
				(font
					(size 1 1)
					(thickness 0.15)
				)
			)
		)
		(property "Voltage" "16V"
			(at 0 0 270)
			(unlocked yes)
			(layer "F.Fab")
			(hide yes)
			(effects
				(font
					(size 1 1)
					(thickness 0.15)
				)
			)
		)
		(property "Dielectric" "X7R"
			(at 0 0 270)
			(unlocked yes)
			(layer "F.Fab")
			(hide yes)
			(effects
				(font
					(size 1 1)
					(thickness 0.15)
				)
			)
		)
		(sheetname "/X710-AT2 PCIe/")
		(sheetfile "x710-at2-pcie.kicad_sch")
		(attr smd)
		(fp_rect
			(start -0.925 -0.47)
			(end 0.925 0.47)
			(stroke
				(width 0.05)
				(type default)
			)
			(fill no)
			(layer "F.CrtYd")
		)
		(fp_line
			(start -0.494 0.248)
			(end -0.494 -0.25)
			(stroke
				(width 0.15)
				(type solid)
			)
			(layer "F.Fab")
		)
		(fp_line
			(start 0.504 0.248)
			(end -0.494 0.248)
			(stroke
				(width 0.15)
				(type solid)
			)
			(layer "F.Fab")
		)
		(fp_line
			(start -0.494 -0.25)
			(end 0.504 -0.25)
			(stroke
				(width 0.15)
				(type solid)
			)
			(layer "F.Fab")
		)
		(fp_line
			(start 0.504 -0.25)
			(end 0.504 0.248)
			(stroke
				(width 0.15)
				(type solid)
			)
			(layer "F.Fab")
		)
		(pad "1" smd roundrect
			(at -0.48 0 270)
			(size 0.59 0.64)
			(layers "F.Cu" "F.Mask" "F.Paste")
			(roundrect_rratio 0.25)
			(net 13 "/OCuLink/PCIe_{x4}.TX0+")
			(pintype "passive")
		)
		(pad "2" smd roundrect
			(at 0.48 0 270)
			(size 0.59 0.64)
			(layers "F.Cu" "F.Mask" "F.Paste")
			(roundrect_rratio 0.25)
			(net 32 "/X710-AT2 PCIe/PCIe_{x4}_AC.TX0+")
			(pintype "passive")
		)
	)
	(footprint "antmicro-footprints:SOT-23-3"
		(layer "F.Cu")
		(at 55.65 78 90)
		(property "Reference" "Q4"
			(at 0.85 1.44 90)
			(layer "F.SilkS")
			(effects
				(font
					(size 0.7 0.7)
					(thickness 0.15)
				)
				(justify left bottom)
			)
		)
		(property "Value" "2N7002_SOT-23-3"
			(at -1.9 2.7 90)
			(layer "F.Fab")
			(hide yes)
			(effects
				(font
					(size 0.7 0.7)
					(thickness 0.15)
				)
				(justify left bottom)
			)
		)
		(property "Datasheet" "https://www.onsemi.com/pub/Collateral/NDS7002A-D.PDF"
			(at 0 0 90)
			(layer "F.Fab")
			(hide yes)
			(effects
				(font
					(size 1.27 1.27)
					(thickness 0.15)
				)
			)
		)
		(property "Description" "Power MOSFET, N Channel, 60 V, 115 mA, 1.2 ohm, SOT-23, Surface Mount"
			(at 0 0 90)
			(layer "F.Fab")
			(hide yes)
			(effects
				(font
					(size 1.27 1.27)
					(thickness 0.15)
				)
			)
		)
		(property "MPN" "2N7002"
			(at 0 0 90)
			(unlocked yes)
			(layer "F.Fab")
			(hide yes)
			(effects
				(font
					(size 1 1)
					(thickness 0.15)
				)
			)
		)
		(property "Manufacturer" "ON Semiconductor"
			(at 0 0 90)
			(unlocked yes)
			(layer "F.Fab")
			(hide yes)
			(effects
				(font
					(size 1 1)
					(thickness 0.15)
				)
			)
		)
		(property "Author" "Antmicro"
			(at 0 0 90)
			(unlocked yes)
			(layer "F.Fab")
			(hide yes)
			(effects
				(font
					(size 1 1)
					(thickness 0.15)
				)
			)
		)
		(property "License" "Apache-2.0"
			(at 0 0 90)
			(unlocked yes)
			(layer "F.Fab")
			(hide yes)
			(effects
				(font
					(size 1 1)
					(thickness 0.15)
				)
			)
		)
		(sheetname "/Power/")
		(sheetfile "power.kicad_sch")
		(attr smd)
		(fp_line
			(start 0.7 -1.5)
			(end -0.7 -1.5)
			(stroke
				(width 0.15)
				(type solid)
			)
			(layer "F.SilkS")
		)
		(fp_line
			(start -0.85 -1.35)
			(end -0.7 -1.5)
			(stroke
				(width 0.15)
				(type solid)
			)
			(layer "F.SilkS")
		)
		(fp_line
			(start -1.45 -1.35)
			(end -0.85 -1.35)
			(stroke
				(width 0.15)
				(type solid)
			)
			(layer "F.SilkS")
		)
		(fp_line
			(start 0.7 -0.4)
			(end 0.7 -1.5)
			(stroke
				(width 0.15)
				(type solid)
			)
			(layer "F.SilkS")
		)
		(fp_line
			(start 0.7 0.4)
			(end 0.7 1.5)
			(stroke
				(width 0.15)
				(type solid)
			)
			(layer "F.SilkS")
		)
		(fp_line
			(start 0.7 1.5)
			(end -0.7 1.5)
			(stroke
				(width 0.15)
				(type solid)
			)
			(layer "F.SilkS")
		)
		(fp_line
			(start -0.7 1.5)
			(end -0.7 1.35)
			(stroke
				(width 0.15)
				(type solid)
			)
			(layer "F.SilkS")
		)
		(fp_line
			(start 0.825 -1.6)
			(end 0.825 -0.45)
			(stroke
				(width 0.05)
				(type solid)
			)
			(layer "F.CrtYd")
		)
		(fp_line
			(start -0.9 -1.6)
			(end 0.825 -1.6)
			(stroke
				(width 0.05)
				(type solid)
			)
			(layer "F.CrtYd")
		)
		(fp_line
			(start -0.9 -1.6)
			(end -0.9 -1.4)
			(stroke
				(width 0.05)
				(type solid)
			)
			(layer "F.CrtYd")
		)
		(fp_line
			(start -0.9 -1.4)
			(end -1.75 -1.4)
			(stroke
				(width 0.05)
				(type solid)
			)
			(layer "F.CrtYd")
		)
		(fp_line
			(start -0.85 -0.5)
			(end -1.75 -0.5)
			(stroke
				(width 0.05)
				(type solid)
			)
			(layer "F.CrtYd")
		)
		(fp_line
			(start -1.75 -0.5)
			(end -1.75 -1.4)
			(stroke
				(width 0.05)
				(type solid)
			)
			(layer "F.CrtYd")
		)
		(fp_line
			(start 1.75 -0.45)
			(end 1.75 0.45)
			(stroke
				(width 0.05)
				(type solid)
			)
			(layer "F.CrtYd")
		)
		(fp_line
			(start 0.825 -0.45)
			(end 1.75 -0.45)
			(stroke
				(width 0.05)
				(type solid)
			)
			(layer "F.CrtYd")
		)
		(fp_line
			(start 1.75 0.45)
			(end 0.85 0.45)
			(stroke
				(width 0.05)
				(type solid)
			)
			(layer "F.CrtYd")
		)
		(fp_line
			(start 0.85 0.45)
			(end 0.85 1.65)
			(stroke
				(width 0.05)
				(type solid)
			)
			(layer "F.CrtYd")
		)
		(fp_line
			(start -0.85 0.5)
			(end -0.85 -0.5)
			(stroke
				(width 0.05)
				(type solid)
			)
			(layer "F.CrtYd")
		)
		(fp_line
			(start -1.75 0.5)
			(end -0.85 0.5)
			(stroke
				(width 0.05)
				(type solid)
			)
			(layer "F.CrtYd")
		)
		(fp_line
			(start -0.85 1.4)
			(end -1.75 1.4)
			(stroke
				(width 0.05)
				(type solid)
			)
			(layer "F.CrtYd")
		)
		(fp_line
			(start -1.75 1.4)
			(end -1.75 0.5)
			(stroke
				(width 0.05)
				(type solid)
			)
			(layer "F.CrtYd")
		)
		(fp_line
			(start 0.85 1.65)
			(end -0.85 1.65)
			(stroke
				(width 0.05)
				(type solid)
			)
			(layer "F.CrtYd")
		)
		(fp_line
			(start -0.85 1.65)
			(end -0.85 1.4)
			(stroke
				(width 0.05)
				(type solid)
			)
			(layer "F.CrtYd")
		)
		(fp_line
			(start -0.437 -1.526)
			(end 0.688 -1.526)
			(stroke
				(width 0.15)
				(type solid)
			)
			(layer "F.Fab")
		)
		(fp_line
			(start -0.437 -1.526)
			(end -0.712 -1.325)
			(stroke
				(width 0.15)
				(type solid)
			)
			(layer "F.Fab")
		)
		(fp_line
			(start -0.712 -1.325)
			(end -0.712 1.523)
			(stroke
				(width 0.15)
				(type solid)
			)
			(layer "F.Fab")
		)
		(fp_line
			(start 0.688 1.519)
			(end 0.688 -1.52)
			(stroke
				(width 0.15)
				(type solid)
			)
			(layer "F.Fab")
		)
		(fp_line
			(start -0.712 1.519)
			(end 0.688 1.519)
			(stroke
				(width 0.15)
				(type solid)
			)
			(layer "F.Fab")
		)
		(pad "1" smd roundrect
			(at -1.1 -0.951 90)
			(size 1 0.6)
			(layers "F.Cu" "F.Mask" "F.Paste")
			(roundrect_rratio 0.15)
			(net 378 "/Power/DVDD_PG")
			(pinfunction "G")
			(pintype "input")
		)
		(pad "2" smd roundrect
			(at -1.1 0.949 90)
			(size 1 0.6)
			(layers "F.Cu" "F.Mask" "F.Paste")
			(roundrect_rratio 0.15)
			(net 28 "GND")
			(pinfunction "S")
			(pintype "passive")
		)
		(pad "3" smd roundrect
			(at 1.1 -0.0005 90)
			(size 1 0.6)
			(layers "F.Cu" "F.Mask" "F.Paste")
			(roundrect_rratio 0.15)
			(net 89 "Net-(D11-C)")
			(pinfunction "D")
			(pintype "passive")
		)
	)
	(footprint "antmicro-footprints:C_0603_1608Metric_EIA"
		(layer "F.Cu")
		(at 77.2 83.65 180)
		(descr "Capacitor SMD 0603, IPC-7351 Density Level A")
		(tags "Capacitor 0603")
		(property "Reference" "C153"
			(at -1.4 7.772 0)
			(layer "F.SilkS")
			(effects
				(font
					(size 0.7 0.7)
					(thickness 0.15)
				)
				(justify right top)
			)
		)
		(property "Value" "C_22u_16V_0603"
			(at -1.42757 1.770288 0)
			(layer "F.Fab")
			(hide yes)
			(effects
				(font
					(size 0.7 0.7)
					(thickness 0.15)
				)
				(justify right top)
			)
		)
		(property "Datasheet" "https://product.samsungsem.com/mlcc/CL10A226MO7JZN.do"
			(at 0 0 0)
			(layer "F.Fab")
			(hide yes)
			(effects
				(font
					(size 1.27 1.27)
					(thickness 0.15)
				)
			)
		)
		(property "Description" "SMD Multilayer Ceramic Capacitor"
			(at 0 0 0)
			(layer "F.Fab")
			(hide yes)
			(effects
				(font
					(size 1.27 1.27)
					(thickness 0.15)
				)
			)
		)
		(property "MPN" "CL10A226MO7JZNC"
			(at 0 0 180)
			(unlocked yes)
			(layer "F.Fab")
			(hide yes)
			(effects
				(font
					(size 1 1)
					(thickness 0.15)
				)
			)
		)
		(property "Manufacturer" "Samsung Electro-Mechanics"
			(at 0 0 180)
			(unlocked yes)
			(layer "F.Fab")
			(hide yes)
			(effects
				(font
					(size 1 1)
					(thickness 0.15)
				)
			)
		)
		(property "License" "Apache-2.0"
			(at 0 0 180)
			(unlocked yes)
			(layer "F.Fab")
			(hide yes)
			(effects
				(font
					(size 1 1)
					(thickness 0.15)
				)
			)
		)
		(property "Author" "Antmicro"
			(at 0 0 180)
			(unlocked yes)
			(layer "F.Fab")
			(hide yes)
			(effects
				(font
					(size 1 1)
					(thickness 0.15)
				)
			)
		)
		(property "Val" "22u"
			(at 0 0 180)
			(unlocked yes)
			(layer "F.Fab")
			(hide yes)
			(effects
				(font
					(size 1 1)
					(thickness 0.15)
				)
			)
		)
		(property "Voltage" "16V"
			(at 0 0 180)
			(unlocked yes)
			(layer "F.Fab")
			(hide yes)
			(effects
				(font
					(size 1 1)
					(thickness 0.15)
				)
			)
		)
		(property "Dielectric" ""
			(at 0 0 180)
			(unlocked yes)
			(layer "F.Fab")
			(hide yes)
			(effects
				(font
					(size 1 1)
					(thickness 0.15)
				)
			)
		)
		(sheetname "/X710-AT2 power/")
		(sheetfile "x710-at2-power.kicad_sch")
		(attr smd)
		(fp_line
			(start -0.15 0.55)
			(end 0.15 0.55)
			(stroke
				(width 0.15)
				(type solid)
			)
			(layer "F.SilkS")
		)
		(fp_line
			(start -0.15 -0.55)
			(end 0.15 -0.55)
			(stroke
				(width 0.15)
				(type solid)
			)
			(layer "F.SilkS")
		)
		(fp_rect
			(start -1.25 -0.65)
			(end 1.25 0.65)
			(stroke
				(width 0.05)
				(type solid)
			)
			(fill no)
			(layer "F.CrtYd")
		)
		(fp_rect
			(start -0.8 -0.45)
			(end 0.8 0.45)
			(stroke
				(width 0.15)
				(type solid)
			)
			(fill no)
			(layer "F.Fab")
		)
		(pad "1" smd roundrect
			(at -0.7 0 180)
			(size 0.8 1.1)
			(layers "F.Cu" "F.Mask" "F.Paste")
			(roundrect_rratio 0.2)
			(net 28 "GND")
			(pintype "passive")
		)
		(pad "2" smd roundrect
			(at 0.7 0 180)
			(size 0.8 1.1)
			(layers "F.Cu" "F.Mask" "F.Paste")
			(roundrect_rratio 0.2)
			(net 7 "+3V3")
			(pintype "passive")
		)
	)
)
